#ISCELL
  pure_quanta quanta_title_block_c *
  *
#ISCELL
  standard offpage *
  page410_i1
#ISCELL
  standard offpage *
  page410_i2
#CELL
  pure_quanta q_res *
  page410_i20
#ISCELL
  pure_quanta_power universal_gnd *
  page410_i21
#ISCELL
  pure_quanta_power universal_gnd *
  page410_i22
#ISCELL
  pure_quanta_power p1v0 *
  page410_i23
#CELL
  pure_quanta q_cap *
  page410_i24
#ISCELL
  pure_quanta_power universal_gnd *
  page410_i25
#ISCELL
  pure_quanta_power universal_gnd *
  page410_i26
#CELL
  pure_quanta m24m02drmn6tp *
  page410_i5
#CELL
  pure_quanta q_res *
  page410_i6
#CELL
  pure_quanta q_res *
  page410_i7
